# T6G (Grand Teton) — schematic netlist excerpt (pin names and nets, part order shuffled) for the footprints in the layout excerpt that follows; sources: Cadence DE-HDL packaged netlist, KiCad conversion of 04192023_DAF0TMB3IC0_F0TG_MB_C_brd_V02_OCP.brd

C942  Q_CAP_DIFFBUS  DIFF BUS_0.22UF 6.3V 20% X6S  pkg C0201  page 63 : \1\ = P5E_CPU0_P1_TX_C_DN<11> ; \2\ = P5E_CPU0_P1_TX_DN<11>
R4490  Q_RES  4.75K 1% EMPTY  pkg 0402LF  page 182 : A = CLK_9ZXL045_P0_SADR0 ; B = GND

(kicad_pcb
	(version 20260206)
	(generator "pcbnew")
	(generator_version "10.0")
	(general
		(thickness 1.6)
		(legacy_teardrops no)
	)
	(paper "A4")
	(title_block
		(title "04192023_DAF0TMB3IC0_F0TG_MB_C_brd_V02_OCP.brd")
		(comment 1 "Grand Teton / footprints 701-702 of 8354")
	)
	(layers
		(0 "F.Cu" signal "TOP")
		(4 "In1.Cu" signal "GND")
		(6 "In2.Cu" signal "IN1")
		(8 "In3.Cu" signal "GND1")
		(10 "In4.Cu" signal "IN2")
		(12 "In5.Cu" signal "GND2")
		(14 "In6.Cu" signal "IN3")
		(16 "In7.Cu" signal "GND3")
		(18 "In8.Cu" signal "VCC")
		(20 "In9.Cu" signal "VCC1")
		(22 "In10.Cu" signal "GND4")
		(24 "In11.Cu" signal "IN4")
		(26 "In12.Cu" signal "GND5")
		(28 "In13.Cu" signal "IN5")
		(30 "In14.Cu" signal "GND6")
		(32 "In15.Cu" signal "IN6")
		(34 "In16.Cu" signal "GND7")
		(2 "B.Cu" signal "BOTTOM")
		(9 "F.Adhes" user "F.Adhesive")
		(11 "B.Adhes" user "B.Adhesive")
		(13 "F.Paste" user "Package Geometry/Pastemask Top")
		(15 "B.Paste" user "Package Geometry/Pastemask Bottom")
		(5 "F.SilkS" user "Ref Des/Silkscreen Top")
		(7 "B.SilkS" user "Ref Des/Silkscreen Bottom")
		(1 "F.Mask" user "Board Geometry/Soldermask Top")
		(3 "B.Mask" user "Board Geometry/Soldermask Bottom")
		(17 "Dwgs.User" user "User.Drawings")
		(19 "Cmts.User" user "User.Comments")
		(21 "Eco1.User" user "User.Eco1")
		(23 "Eco2.User" user "User.Eco2")
		(25 "Edge.Cuts" user "Board Geometry/Outline")
		(27 "Margin" user)
		(31 "F.CrtYd" user "Package Geometry/Place Bound Top")
		(29 "B.CrtYd" user "Package Geometry/Place Bound Bottom")
		(35 "F.Fab" user "Ref Des/Assembly Top")
		(33 "B.Fab" user "Ref Des/Assembly Bottom")
	)
	(footprint ""
		(layer "F.Cu")
		(at 279.527 -417.195 180)
		(property "Reference" "R4490"
			(at 0 0 180)
			(layer "F.SilkS")
			(hide yes)
			(effects
				(font
					(size 1.27 1.27)
				)
			)
		)
		(property "Value" ""
			(at 0 0 180)
			(layer "F.Fab")
			(effects
				(font
					(size 1.27 1.27)
				)
			)
		)
		(duplicate_pad_numbers_are_jumpers no)
		(fp_line
			(start 0.7874 0.4064)
			(end -0.7874 0.4064)
			(stroke
				(width 0.1524)
				(type default)
			)
			(layer "F.SilkS")
		)
		(fp_line
			(start 0.7874 -0.4064)
			(end 0.7874 0.4064)
			(stroke
				(width 0.1524)
				(type default)
			)
			(layer "F.SilkS")
		)
		(fp_line
			(start -0.7874 0.4064)
			(end -0.7874 -0.4064)
			(stroke
				(width 0.1524)
				(type default)
			)
			(layer "F.SilkS")
		)
		(fp_line
			(start -0.7874 -0.4064)
			(end 0.7874 -0.4064)
			(stroke
				(width 0.1524)
				(type default)
			)
			(layer "F.SilkS")
		)
		(fp_line
			(start 0.67945 0.3048)
			(end 0.120396 0.3048)
			(stroke
				(width 0.1)
				(type default)
			)
			(layer "F.Fab")
		)
		(fp_line
			(start 0.67945 -0.3048)
			(end 0.67945 0.3048)
			(stroke
				(width 0.1)
				(type default)
			)
			(layer "F.Fab")
		)
		(fp_line
			(start 0.12065 -0.2794)
			(end 0.12065 -0.3048)
			(stroke
				(width 0.1)
				(type default)
			)
			(layer "F.Fab")
		)
		(fp_line
			(start 0.12065 -0.3048)
			(end 0.67945 -0.3048)
			(stroke
				(width 0.1)
				(type default)
			)
			(layer "F.Fab")
		)
		(fp_line
			(start 0.120396 0.3048)
			(end 0.120396 0.2794)
			(stroke
				(width 0.1)
				(type default)
			)
			(layer "F.Fab")
		)
		(fp_line
			(start 0.120396 0.2794)
			(end -0.12065 0.2794)
			(stroke
				(width 0.1)
				(type default)
			)
			(layer "F.Fab")
		)
		(fp_line
			(start -0.12065 0.3048)
			(end -0.67945 0.3048)
			(stroke
				(width 0.1)
				(type default)
			)
			(layer "F.Fab")
		)
		(fp_line
			(start -0.12065 0.2794)
			(end -0.12065 0.3048)
			(stroke
				(width 0.1)
				(type default)
			)
			(layer "F.Fab")
		)
		(fp_line
			(start -0.12065 -0.2794)
			(end 0.12065 -0.2794)
			(stroke
				(width 0.1)
				(type default)
			)
			(layer "F.Fab")
		)
		(fp_line
			(start -0.12065 -0.305054)
			(end -0.12065 -0.2794)
			(stroke
				(width 0.1)
				(type default)
			)
			(layer "F.Fab")
		)
		(fp_line
			(start -0.67945 0.3048)
			(end -0.67945 -0.305054)
			(stroke
				(width 0.1)
				(type default)
			)
			(layer "F.Fab")
		)
		(fp_line
			(start -0.67945 -0.305054)
			(end -0.12065 -0.305054)
			(stroke
				(width 0.1)
				(type default)
			)
			(layer "F.Fab")
		)
		(pad "1" smd circle
			(at -0.40005 0 180)
			(size 0 0)
			(layers "F.Cu" "F.Mask" "F.Paste")
			(net "CLK_9ZXL045_P0_SADR0")
		)
		(pad "2" smd circle
			(at 0.40005 0 180)
			(size 0 0)
			(layers "F.Cu" "F.Mask" "F.Paste")
			(net "GND")
		)
	)
	(footprint ""
		(layer "F.Cu")
		(at 352.853244 -381.41783 -90)
		(property "Reference" "C942"
			(at 0 0 270)
			(layer "F.SilkS")
			(hide yes)
			(effects
				(font
					(size 1.27 1.27)
				)
			)
		)
		(property "Value" ""
			(at 0 0 270)
			(layer "F.Fab")
			(effects
				(font
					(size 1.27 1.27)
				)
			)
		)
		(duplicate_pad_numbers_are_jumpers no)
		(fp_line
			(start -0.299974 0.150114)
			(end -0.299974 -0.150114)
			(stroke
				(width 0.1)
				(type default)
			)
			(layer "F.Fab")
		)
		(fp_line
			(start 0.299974 0.150114)
			(end -0.299974 0.150114)
			(stroke
				(width 0.1)
				(type default)
			)
			(layer "F.Fab")
		)
		(fp_line
			(start -0.299974 -0.150114)
			(end 0.299974 -0.150114)
			(stroke
				(width 0.1)
				(type default)
			)
			(layer "F.Fab")
		)
		(fp_line
			(start 0.299974 -0.150114)
			(end 0.299974 0.150114)
			(stroke
				(width 0.1)
				(type default)
			)
			(layer "F.Fab")
		)
		(pad "1" smd rect
			(at -0.2667 0 270)
			(size 0.3048 0.381)
			(layers "F.Cu" "F.Mask" "F.Paste")
			(net "P5E_CPU0_P1_TX_C_DN<11>")
		)
		(pad "2" smd rect
			(at 0.2667 0 270)
			(size 0.3048 0.381)
			(layers "F.Cu" "F.Mask" "F.Paste")
			(net "P5E_CPU0_P1_TX_DN<11>")
		)
	)
)
